# TIMECARD (Time Appliance Project (Time Card)) — schematic netlist excerpt (pin names and nets, part order shuffled) for the footprints in the layout excerpt that follows; sources: Cadence DE-HDL packaged netlist, KiCad conversion of R4006-B0001-02_R01.brd

C105  CAPACITOR  0.1UF 10V 10%  pkg SMC_0402R_H022  page 14 : \1\ = XP1R0V_FPGA_MGTAVCC ; \2\ = SG
C128  CAPACITOR  4.7UF 6.3V 20%  pkg SMC_0402R_H026  page 14 : \1\ = XP1R8V_FPGA_VCCAUX ; \2\ = SG

(kicad_pcb
	(version 20260206)
	(generator "pcbnew")
	(generator_version "10.0")
	(general
		(thickness 1.6)
		(legacy_teardrops no)
	)
	(paper "A4")
	(title_block
		(title "timecard-production-celestica-r4006 — R4006-B0001-02_R01.brd")
		(comment 1 "Time Appliance Project (Time Card) / footprints 1015-1016 of 1113")
	)
	(layers
		(0 "F.Cu" signal "TOP")
		(4 "In1.Cu" signal "L02_GND1")
		(6 "In2.Cu" signal "L03_SIG1")
		(8 "In3.Cu" signal "L04_GND2")
		(10 "In4.Cu" signal "L05_VCC1")
		(12 "In5.Cu" signal "L06_VCC2")
		(14 "In6.Cu" signal "L07_GND3")
		(16 "In7.Cu" signal "L08_SIG2")
		(18 "In8.Cu" signal "L09_GND4")
		(2 "B.Cu" signal "BOTTOM")
		(9 "F.Adhes" user "F.Adhesive")
		(11 "B.Adhes" user "B.Adhesive")
		(13 "F.Paste" user "Package Geometry/Pastemask Top")
		(15 "B.Paste" user "Package Geometry/Pastemask Bottom")
		(5 "F.SilkS" user "Ref Des/Silkscreen Top")
		(7 "B.SilkS" user "Ref Des/Silkscreen Bottom")
		(1 "F.Mask" user "Board Geometry/Soldermask Top")
		(3 "B.Mask" user "Board Geometry/Soldermask Bottom")
		(17 "Dwgs.User" user "User.Drawings")
		(19 "Cmts.User" user "User.Comments")
		(21 "Eco1.User" user "User.Eco1")
		(23 "Eco2.User" user "User.Eco2")
		(25 "Edge.Cuts" user "Board Geometry/Outline")
		(27 "Margin" user)
		(31 "F.CrtYd" user "Package Geometry/Place Bound Top")
		(29 "B.CrtYd" user "Package Geometry/Place Bound Bottom")
		(35 "F.Fab" user "Ref Des/Assembly Top")
		(33 "B.Fab" user "Ref Des/Assembly Bottom")
	)
	(footprint ""
		(layer "B.Cu")
		(at 102.84714 -41.32326 -90)
		(property "Reference" "C105"
			(at 1.016 41.50995 270)
			(unlocked yes)
			(layer "B.SilkS")
			(effects
				(font
					(size 0.635 0.4064)
					(thickness 0.1524)
				)
				(justify mirror)
			)
		)
		(property "Value" "VAL*"
			(at 0 3.718306 270)
			(unlocked yes)
			(layer "B.Fab")
			(hide yes)
			(effects
				(font
					(size 0.7874 0.5842)
					(thickness 0.127)
				)
				(justify mirror)
			)
		)
		(property "Tolerance" "TOL*"
			(at 0 4.861306 270)
			(unlocked yes)
			(layer "Cmts.User")
			(hide yes)
			(effects
				(font
					(size 0.7874 0.5842)
					(thickness 0.127)
				)
				(justify mirror)
			)
		)
		(property "User Part Number" "PARTNUM*"
			(at 0 2.575306 270)
			(unlocked yes)
			(layer "Cmts.User")
			(hide yes)
			(effects
				(font
					(size 0.7874 0.5842)
					(thickness 0.127)
				)
				(justify mirror)
			)
		)
		(property "Device Type" "CAPACITOR-G105-0B104-CK,0.1UF,A"
			(at 0 1.432306 270)
			(unlocked yes)
			(layer "B.Fab")
			(hide yes)
			(effects
				(font
					(size 0.7874 0.5842)
					(thickness 0.127)
				)
				(justify mirror)
			)
		)
		(duplicate_pad_numbers_are_jumpers no)
		(fp_line
			(start -0.970026 0.4699)
			(end 0.970026 0.4699)
			(stroke
				(width 0.1)
				(type default)
			)
			(layer "B.SilkS")
		)
		(fp_line
			(start 0.970026 0.4699)
			(end 0.970026 -0.4699)
			(stroke
				(width 0.1)
				(type default)
			)
			(layer "B.SilkS")
		)
		(fp_line
			(start -0.970026 -0.4699)
			(end -0.970026 0.4699)
			(stroke
				(width 0.1)
				(type default)
			)
			(layer "B.SilkS")
		)
		(fp_line
			(start 0.970026 -0.4699)
			(end -0.970026 -0.4699)
			(stroke
				(width 0.1)
				(type default)
			)
			(layer "B.SilkS")
		)
		(fp_poly
			(pts
				(xy 0.970026 0.4699) (xy -0.970026 0.4699) (xy -0.970026 -0.4699) (xy 0.970026 -0.4699)
			)
			(stroke
				(width 0)
				(type default)
			)
			(fill no)
			(layer "B.CrtYd")
		)
		(fp_line
			(start -0.508 0.3048)
			(end 0.508 0.3048)
			(stroke
				(width 0.1)
				(type default)
			)
			(layer "B.Fab")
		)
		(fp_line
			(start 0.508 0.3048)
			(end 0.508 -0.3048)
			(stroke
				(width 0.1)
				(type default)
			)
			(layer "B.Fab")
		)
		(fp_line
			(start -0.508 -0.3048)
			(end -0.508 0.3048)
			(stroke
				(width 0.1)
				(type default)
			)
			(layer "B.Fab")
		)
		(fp_line
			(start 0.508 -0.3048)
			(end -0.508 -0.3048)
			(stroke
				(width 0.1)
				(type default)
			)
			(layer "B.Fab")
		)
		(pad "1" smd circle
			(at 0.500126 0 90)
			(size 0.635 0.635)
			(layers "B.Cu" "B.Mask" "B.Paste")
			(net "XP1R0V_FPGA_MGTAVCC")
		)
		(pad "2" smd circle
			(at -0.500126 0 90)
			(size 0.635 0.635)
			(layers "B.Cu" "B.Mask" "B.Paste")
			(net "SG")
		)
	)
	(footprint ""
		(layer "B.Cu")
		(at 112.880394 -44.577 180)
		(property "Reference" "C128"
			(at 43.307254 -1.88595 0)
			(unlocked yes)
			(layer "B.SilkS")
			(effects
				(font
					(size 0.635 0.4064)
					(thickness 0.1524)
				)
				(justify mirror)
			)
		)
		(property "Value" "VAL*"
			(at -0.02032 2.13233 180)
			(unlocked yes)
			(layer "B.Fab")
			(hide yes)
			(effects
				(font
					(size 0.7874 0.5842)
					(thickness 0.1524)
				)
				(justify mirror)
			)
		)
		(property "Device Type" "CAPACITOR-G105-0F475-BM,4.7UF,A"
			(at -0.008382 1.210564 180)
			(unlocked yes)
			(layer "B.Fab")
			(hide yes)
			(effects
				(font
					(size 0.7874 0.5842)
					(thickness 0.1524)
				)
				(justify mirror)
			)
		)
		(property "User Part Number" "PARTNUM*"
			(at -0.02032 4.024884 180)
			(unlocked yes)
			(layer "Cmts.User")
			(hide yes)
			(effects
				(font
					(size 0.7874 0.5842)
					(thickness 0.1524)
				)
				(justify mirror)
			)
		)
		(property "Tolerance" "TOL*"
			(at -0.044704 3.05435 180)
			(unlocked yes)
			(layer "Cmts.User")
			(hide yes)
			(effects
				(font
					(size 0.7874 0.5842)
					(thickness 0.1524)
				)
				(justify mirror)
			)
		)
		(duplicate_pad_numbers_are_jumpers no)
		(fp_line
			(start 1.143 0.5588)
			(end -1.143 0.5588)
			(stroke
				(width 0.1)
				(type default)
			)
			(layer "B.SilkS")
		)
		(fp_line
			(start 1.143 -0.5588)
			(end 1.143 0.5588)
			(stroke
				(width 0.1)
				(type default)
			)
			(layer "B.SilkS")
		)
		(fp_line
			(start -1.143 0.5588)
			(end -1.143 -0.5588)
			(stroke
				(width 0.1)
				(type default)
			)
			(layer "B.SilkS")
		)
		(fp_line
			(start -1.143 -0.5588)
			(end 1.143 -0.5588)
			(stroke
				(width 0.1)
				(type default)
			)
			(layer "B.SilkS")
		)
		(fp_rect
			(start 1.143 -0.5588)
			(end -1.143 0.5588)
			(stroke
				(width 0)
				(type default)
			)
			(fill no)
			(layer "B.CrtYd")
		)
		(fp_line
			(start 0.508 0.3048)
			(end -0.508 0.3048)
			(stroke
				(width 0.1)
				(type default)
			)
			(layer "B.Fab")
		)
		(fp_line
			(start 0.508 -0.3048)
			(end 0.508 0.3048)
			(stroke
				(width 0.1)
				(type default)
			)
			(layer "B.Fab")
		)
		(fp_line
			(start -0.508 0.3048)
			(end -0.508 -0.3048)
			(stroke
				(width 0.1)
				(type default)
			)
			(layer "B.Fab")
		)
		(fp_line
			(start -0.508 -0.3048)
			(end 0.508 -0.3048)
			(stroke
				(width 0.1)
				(type default)
			)
			(layer "B.Fab")
		)
		(pad "1" smd rect
			(at 0.5334 0)
			(size 0.7112 0.6096)
			(layers "B.Cu" "B.Mask" "B.Paste")
			(net "XP1R8V_FPGA_VCCAUX")
		)
		(pad "2" smd rect
			(at -0.5334 0)
			(size 0.7112 0.6096)
			(layers "B.Cu" "B.Mask" "B.Paste")
			(net "SG")
		)
		(zone
			(layer "B.Cu")
			(hatch none 0.5)
			(connect_pads
				(clearance 0)
			)
			(min_thickness 0.25)
			(keepout
				(tracks allowed)
				(vias not_allowed)
				(pads allowed)
				(copperpour not_allowed)
				(footprints allowed)
			)
			(placement
				(enabled no)
				(sheetname "")
			)
			(fill
				(thermal_gap 0.5)
				(thermal_bridge_width 0.5)
				(island_removal_mode 0)
			)
			(polygon
				(pts
					(xy 112.804194 -44.2722) (xy 112.956594 -44.2722) (xy 112.956594 -44.8818) (xy 112.804194 -44.8818)
				)
			)
		)
	)
)
